FILE_TYPE = MULTI_PHYS_TABLE;

PART 'MP5991GLUZ'

{========================================================================================}
:VALUE         | PART_TYPE | MATERIAL | PART_NUMBER    = STANDARD    | LIFECYCLE     | PART_NUMBER   | JEDEC_TYPE         | DESCRIPTION               | MANUFTR | MANUF_PN      | RD_CMPLS_LVL | CMPLS_LVL | FROM_PJ    | CLASS | DIP_SMD | DATA                  | EE_CHECK_LIST | FP_ECN | PSL | CREATOR | STATUS | MSD | ESD_CDM | ESD_HBM | ESD_MM | PIN_LENGTH_SHORT_PIN | PIN_LENGTH_LONG_PIN | CREATEDAY  ;
{========================================================================================}
 'MP5991GLU-Z' | 'SMLF'    | 'IC'     | 'AL005991A00'(!) = ''               | ''               | 'AL005991A00' |'LGA32_TH_0-5_5X5'| 'IC(32P)MP5991GLU-Z(LGA)' | 'MPS'   | 'MP5991GLU-Z' | 'EP(V1)'     | ''        | 'F0E-GREG' | 'IC'  | ''      | 'MPS_MP5991GLU-Z.pdf' | ''            | ''     | ''  | ''      | ''     | ''  | ''      | ''      | ''     | '0 MILS'             | '0 MILS'            | '20211019'
 'MP5991GLU-Z' | 'SMLF'    | 'EMPTY'  | 'AL005991A00'(!) = ''               | ''               | 'AL005991A00' |'LGA32_TH_0-5_5X5'| 'IC(32P)MP5991GLU-Z(LGA)' | 'MPS'   | 'MP5991GLU-Z' | 'EP(V1)'     | ''        | 'F0E-GREG' | 'IC'  | ''      | 'MPS_MP5991GLU-Z.pdf' | ''            | ''     | ''  | ''      | ''     | ''  | ''      | ''      | ''     | '0 MILS'             | '0 MILS'            | '20211019'

END_PART

END.

